(kicad_pcb
	(version 20241229)
	(generator "pcbnew")
	(generator_version "9.0")
	(general
		(thickness 1.6296)
		(legacy_teardrops no)
	)
	(paper "A3")
	(title_block
		(title "Thunderbolt to 10GbE adapter")
		(date "2026-04-21")
		(rev "1.1.0")
		(company "Antmicro Ltd")
		(comment 1 "www.antmicro.com")
		(comment 9 "footprints 253-257 of 703")
	)
	(layers
		(0 "F.Cu" signal)
		(4 "In1.Cu" signal)
		(6 "In2.Cu" signal)
		(8 "In3.Cu" signal)
		(10 "In4.Cu" signal)
		(12 "In5.Cu" signal)
		(14 "In6.Cu" signal)
		(2 "B.Cu" signal)
		(9 "F.Adhes" user "F.Adhesive")
		(11 "B.Adhes" user "B.Adhesive")
		(13 "F.Paste" user)
		(15 "B.Paste" user)
		(5 "F.SilkS" user "F.Silkscreen")
		(7 "B.SilkS" user "B.Silkscreen")
		(1 "F.Mask" user)
		(3 "B.Mask" user)
		(17 "Dwgs.User" user "User.Drawings")
		(19 "Cmts.User" user "User.Comments")
		(21 "Eco1.User" user "User.Eco1")
		(23 "Eco2.User" user "User.Eco2")
		(25 "Edge.Cuts" user)
		(27 "Margin" user)
		(31 "F.CrtYd" user "F.Courtyard")
		(29 "B.CrtYd" user "B.Courtyard")
		(35 "F.Fab" user)
		(33 "B.Fab" user)
	)
	(footprint "antmicro-footprints:R_0402_1005Metric"
		(layer "F.Cu")
		(at 117 67.5 180)
		(descr "Resistor SMD 0402")
		(tags "resistor SMD 0402")
		(property "Reference" "R135"
			(at -3 -1.4 180)
			(layer "F.SilkS")
			(effects
				(font
					(size 0.7 0.7)
					(thickness 0.15)
				)
				(justify left bottom)
			)
		)
		(property "Value" "R_1k_0402"
			(at -1.011843 1.772047 180)
			(layer "F.Fab")
			(effects
				(font
					(size 0.7 0.7)
					(thickness 0.15)
				)
				(justify left bottom)
			)
		)
		(property "Datasheet" "https://www.bourns.com/docs/product-datasheets/cr.pdf"
			(at 0 0 180)
			(layer "F.Fab")
			(hide yes)
			(effects
				(font
					(size 1.27 1.27)
					(thickness 0.15)
				)
			)
		)
		(property "Description" "SMD Chip Resistor, 1 kohm, ± 1%, 63 mW, 0402 [1005 Metric], Thick Film, General Purpose"
			(at 0 0 180)
			(layer "F.Fab")
			(hide yes)
			(effects
				(font
					(size 1.27 1.27)
					(thickness 0.15)
				)
			)
		)
		(property "MPN" "CR0402-FX-1001GLF"
			(at 0 0 180)
			(unlocked yes)
			(layer "F.Fab")
			(hide yes)
			(effects
				(font
					(size 1 1)
					(thickness 0.15)
				)
			)
		)
		(property "Manufacturer" "Bourns"
			(at 0 0 180)
			(unlocked yes)
			(layer "F.Fab")
			(hide yes)
			(effects
				(font
					(size 1 1)
					(thickness 0.15)
				)
			)
		)
		(property "License" "Apache-2.0"
			(at 0 0 180)
			(unlocked yes)
			(layer "F.Fab")
			(hide yes)
			(effects
				(font
					(size 1 1)
					(thickness 0.15)
				)
			)
		)
		(property "Author" "Antmicro"
			(at 0 0 180)
			(unlocked yes)
			(layer "F.Fab")
			(hide yes)
			(effects
				(font
					(size 1 1)
					(thickness 0.15)
				)
			)
		)
		(property "Val" "1k"
			(at 0 0 180)
			(unlocked yes)
			(layer "F.Fab")
			(hide yes)
			(effects
				(font
					(size 1 1)
					(thickness 0.15)
				)
			)
		)
		(property "Tolerance" "1%"
			(at 0 0 180)
			(unlocked yes)
			(layer "F.Fab")
			(hide yes)
			(effects
				(font
					(size 1 1)
					(thickness 0.15)
				)
			)
		)
		(sheetname "/X710-AT2 RSVD/")
		(sheetfile "x710-at2-rsvd.kicad_sch")
		(attr smd)
		(fp_rect
			(start -0.925 -0.47)
			(end 0.925 0.47)
			(stroke
				(width 0.05)
				(type default)
			)
			(fill no)
			(layer "F.CrtYd")
		)
		(fp_rect
			(start -0.5 -0.25)
			(end 0.5 0.25)
			(stroke
				(width 0.15)
				(type solid)
			)
			(fill no)
			(layer "F.Fab")
		)
		(fp_text user "Author: Antmicro"
			(at -0.95 4.169 180)
			(layer "F.Fab")
			(effects
				(font
					(size 0.7 0.7)
					(thickness 0.15)
				)
				(justify left bottom)
			)
		)
		(fp_text user "${REFERENCE}"
			(at -0.95 3.168 180)
			(layer "F.Fab")
			(effects
				(font
					(size 0.7 0.7)
					(thickness 0.15)
				)
				(justify left bottom)
			)
		)
		(fp_text user "License: Apache-2.0"
			(at -0.95 5.169 180)
			(layer "F.Fab")
			(effects
				(font
					(size 0.7 0.7)
					(thickness 0.15)
				)
				(justify left bottom)
			)
		)
		(pad "1" smd roundrect
			(at -0.48 0 180)
			(size 0.59 0.64)
			(layers "F.Cu" "F.Mask" "F.Paste")
			(roundrect_rratio 0.25)
			(net 91 "/X710-AT2 RSVD/DEBUG_Y16")
			(pintype "passive")
		)
		(pad "2" smd roundrect
			(at 0.48 0 180)
			(size 0.59 0.64)
			(layers "F.Cu" "F.Mask" "F.Paste")
			(roundrect_rratio 0.25)
			(net 86 "/X710-AT2 RSVD/DEBUG_EN")
			(pintype "passive")
		)
	)
	(footprint "antmicro-footprints:SOD-523"
		(layer "F.Cu")
		(at 130.2 70.2)
		(property "Reference" "D14"
			(at -1 -1.8 0)
			(layer "F.SilkS")
			(effects
				(font
					(size 0.7 0.7)
					(thickness 0.15)
				)
				(justify left bottom)
			)
		)
		(property "Value" "RB521S30T1G"
			(at 0 1.499 0)
			(layer "F.Fab")
			(effects
				(font
					(size 0.7 0.7)
					(thickness 0.15)
				)
				(justify left bottom)
			)
		)
		(property "Datasheet" "https://www.onsemi.com/pdf/datasheet/rb521s30t1-d.pdf"
			(at 0 0 0)
			(layer "F.Fab")
			(hide yes)
			(effects
				(font
					(size 1.27 1.27)
					(thickness 0.15)
				)
			)
		)
		(property "Description" "Small Signal Schottky Diode, Single, 30 V, 200 mA, 500 mV, 1 A, 125 °C"
			(at 0 0 0)
			(layer "F.Fab")
			(hide yes)
			(effects
				(font
					(size 1.27 1.27)
					(thickness 0.15)
				)
			)
		)
		(property "MPN" "RB521S30T1G"
			(at 0 0 0)
			(unlocked yes)
			(layer "F.Fab")
			(hide yes)
			(effects
				(font
					(size 1 1)
					(thickness 0.15)
				)
			)
		)
		(property "Manufacturer" "ON Semiconductor"
			(at 0 0 0)
			(unlocked yes)
			(layer "F.Fab")
			(hide yes)
			(effects
				(font
					(size 1 1)
					(thickness 0.15)
				)
			)
		)
		(property "Author" "Antmicro"
			(at 0 0 0)
			(unlocked yes)
			(layer "F.Fab")
			(hide yes)
			(effects
				(font
					(size 1 1)
					(thickness 0.15)
				)
			)
		)
		(property "License" "Apache-2.0"
			(at 0 0 0)
			(unlocked yes)
			(layer "F.Fab")
			(hide yes)
			(effects
				(font
					(size 1 1)
					(thickness 0.15)
				)
			)
		)
		(sheetname "/X710 flash memory/")
		(sheetfile "flash_x710.kicad_sch")
		(attr smd)
		(fp_line
			(start -0.35 -0.5)
			(end -0.35 0.5)
			(stroke
				(width 0.15)
				(type solid)
			)
			(layer "F.SilkS")
		)
		(fp_rect
			(start -1 -0.6)
			(end 1 0.6)
			(stroke
				(width 0.05)
				(type solid)
			)
			(fill no)
			(layer "F.CrtYd")
		)
		(fp_line
			(start -0.652 -0.425)
			(end 0.65 -0.425)
			(stroke
				(width 0.15)
				(type solid)
			)
			(layer "F.Fab")
		)
		(fp_line
			(start -0.652 0.423)
			(end -0.652 -0.425)
			(stroke
				(width 0.15)
				(type solid)
			)
			(layer "F.Fab")
		)
		(fp_line
			(start -0.652 0.423)
			(end 0.65 0.423)
			(stroke
				(width 0.15)
				(type solid)
			)
			(layer "F.Fab")
		)
		(fp_line
			(start -0.35 -0.4)
			(end -0.35 0.4)
			(stroke
				(width 0.15)
				(type solid)
			)
			(layer "F.Fab")
		)
		(fp_line
			(start 0.65 -0.425)
			(end 0.65 0.423)
			(stroke
				(width 0.15)
				(type solid)
			)
			(layer "F.Fab")
		)
		(fp_text user "${REFERENCE}"
			(at -1.276 3.499 0)
			(layer "F.Fab")
			(effects
				(font
					(size 0.7 0.7)
					(thickness 0.15)
				)
				(justify left bottom)
			)
		)
		(fp_text user "License: Apache-2.0"
			(at -1.276 5.9 0)
			(layer "F.Fab")
			(effects
				(font
					(size 0.7 0.7)
					(thickness 0.15)
				)
				(justify left bottom)
			)
		)
		(fp_text user "Author: Antmicro"
			(at -1.276 4.7 0)
			(layer "F.Fab")
			(effects
				(font
					(size 0.7 0.7)
					(thickness 0.15)
				)
				(justify left bottom)
			)
		)
		(pad "1" smd roundrect
			(at -0.701 0)
			(size 0.5 0.6)
			(layers "F.Cu" "F.Mask" "F.Paste")
			(roundrect_rratio 0.25)
			(net 343 "/X710 flash memory/+3V3_FLASH")
			(pinfunction "C")
			(pintype "passive")
		)
		(pad "2" smd roundrect
			(at 0.699 0)
			(size 0.5 0.6)
			(layers "F.Cu" "F.Mask" "F.Paste")
			(roundrect_rratio 0.25)
			(net 7 "+3V3")
			(pinfunction "A")
			(pintype "passive")
		)
	)
	(footprint "antmicro-footprints:C_0402_1005Metric"
		(layer "F.Cu")
		(at 144.6 61.75 -90)
		(descr "Capacitor SMD 0402")
		(tags "capacitor SMD 0402")
		(property "Reference" "C322"
			(at 2.25 -1.4 270)
			(layer "F.SilkS")
			(effects
				(font
					(size 0.7 0.7)
					(thickness 0.15)
				)
				(justify left bottom)
			)
		)
		(property "Value" "C_100n_0402"
			(at -1.022927 2.155213 270)
			(layer "F.Fab")
			(effects
				(font
					(size 0.7 0.7)
					(thickness 0.15)
				)
				(justify left bottom)
			)
		)
		(property "Datasheet" "https://www.murata.com/products/productdetail?partno=GRM155R61H104KE14%23"
			(at 0 0 270)
			(layer "F.Fab")
			(hide yes)
			(effects
				(font
					(size 1.27 1.27)
					(thickness 0.15)
				)
			)
		)
		(property "Description" "SMD Multilayer Ceramic Capacitor, 0.1 µF, 50 V, 0402 [1005 Metric], ± 10%, X5R, GRM Series"
			(at 0 0 270)
			(layer "F.Fab")
			(hide yes)
			(effects
				(font
					(size 1.27 1.27)
					(thickness 0.15)
				)
			)
		)
		(property "MPN" "GRM155R61H104KE14D"
			(at 0 0 270)
			(unlocked yes)
			(layer "F.Fab")
			(hide yes)
			(effects
				(font
					(size 1 1)
					(thickness 0.15)
				)
			)
		)
		(property "Manufacturer" "Murata"
			(at 0 0 270)
			(unlocked yes)
			(layer "F.Fab")
			(hide yes)
			(effects
				(font
					(size 1 1)
					(thickness 0.15)
				)
			)
		)
		(property "License" "Apache-2.0"
			(at 0 0 270)
			(unlocked yes)
			(layer "F.Fab")
			(hide yes)
			(effects
				(font
					(size 1 1)
					(thickness 0.15)
				)
			)
		)
		(property "Author" "Antmicro"
			(at 0 0 270)
			(unlocked yes)
			(layer "F.Fab")
			(hide yes)
			(effects
				(font
					(size 1 1)
					(thickness 0.15)
				)
			)
		)
		(property "Val" "100n"
			(at 0 0 270)
			(unlocked yes)
			(layer "F.Fab")
			(hide yes)
			(effects
				(font
					(size 1 1)
					(thickness 0.15)
				)
			)
		)
		(property "Voltage" "50V"
			(at 0 0 270)
			(unlocked yes)
			(layer "F.Fab")
			(hide yes)
			(effects
				(font
					(size 1 1)
					(thickness 0.15)
				)
			)
		)
		(property "Dielectric" "X5R"
			(at 0 0 270)
			(unlocked yes)
			(layer "F.Fab")
			(hide yes)
			(effects
				(font
					(size 1 1)
					(thickness 0.15)
				)
			)
		)
		(sheetname "/Power input/")
		(sheetfile "power_input.kicad_sch")
		(attr smd)
		(fp_rect
			(start -0.925 -0.47)
			(end 0.925 0.47)
			(stroke
				(width 0.05)
				(type default)
			)
			(fill no)
			(layer "F.CrtYd")
		)
		(fp_line
			(start -0.494 0.248)
			(end -0.494 -0.25)
			(stroke
				(width 0.15)
				(type solid)
			)
			(layer "F.Fab")
		)
		(fp_line
			(start 0.504 0.248)
			(end -0.494 0.248)
			(stroke
				(width 0.15)
				(type solid)
			)
			(layer "F.Fab")
		)
		(fp_line
			(start -0.494 -0.25)
			(end 0.504 -0.25)
			(stroke
				(width 0.15)
				(type solid)
			)
			(layer "F.Fab")
		)
		(fp_line
			(start 0.504 -0.25)
			(end 0.504 0.248)
			(stroke
				(width 0.15)
				(type solid)
			)
			(layer "F.Fab")
		)
		(fp_text user "Author: Antmicro"
			(at -0.939 3.399 270)
			(layer "F.Fab")
			(effects
				(font
					(size 0.7 0.7)
					(thickness 0.15)
				)
				(justify left bottom)
			)
		)
		(fp_text user "${REFERENCE}"
			(at -0.939 4.599 270)
			(layer "F.Fab")
			(effects
				(font
					(size 0.7 0.7)
					(thickness 0.15)
				)
				(justify left bottom)
			)
		)
		(fp_text user "License: Apache-2.0"
			(at -0.939 5.799 270)
			(layer "F.Fab")
			(effects
				(font
					(size 0.7 0.7)
					(thickness 0.15)
				)
				(justify left bottom)
			)
		)
		(pad "1" smd roundrect
			(at -0.48 0 270)
			(size 0.59 0.64)
			(layers "F.Cu" "F.Mask" "F.Paste")
			(roundrect_rratio 0.25)
			(net 23 "GND")
			(pintype "passive")
		)
		(pad "2" smd roundrect
			(at 0.48 0 270)
			(size 0.59 0.64)
			(layers "F.Cu" "F.Mask" "F.Paste")
			(roundrect_rratio 0.25)
			(net 13 "/Power input/5V_JACK")
			(pintype "passive")
		)
	)
	(footprint "antmicro-footprints:C_0603_1608Metric"
		(layer "F.Cu")
		(at 161.355 93.574999 180)
		(descr "Capacitor SMD 0603")
		(tags "capacitor 0603")
		(property "Reference" "C180"
			(at -7.695 0 180)
			(layer "F.SilkS")
			(effects
				(font
					(size 0.7 0.7)
					(thickness 0.15)
				)
			)
		)
		(property "Value" "C_10u_10V_X7R_0603"
			(at -1.42757 1.770288 180)
			(layer "F.Fab")
			(effects
				(font
					(size 0.7 0.7)
					(thickness 0.15)
				)
				(justify left bottom)
			)
		)
		(property "Datasheet" "https://www.murata.com/products/productdetail?partno=GRM188Z71A106KA73%23"
			(at 0 0 180)
			(layer "F.Fab")
			(hide yes)
			(effects
				(font
					(size 1.27 1.27)
					(thickness 0.15)
				)
			)
		)
		(property "Description" "SMD Multilayer Ceramic Capacitor,  10µF, 10V, 0603, ±10%, X7R"
			(at 0 0 180)
			(layer "F.Fab")
			(hide yes)
			(effects
				(font
					(size 1.27 1.27)
					(thickness 0.15)
				)
			)
		)
		(property "MPN" "GRM188Z71A106KA73D"
			(at 0 0 180)
			(unlocked yes)
			(layer "F.Fab")
			(hide yes)
			(effects
				(font
					(size 1 1)
					(thickness 0.15)
				)
			)
		)
		(property "Val" "10u"
			(at 0 0 180)
			(unlocked yes)
			(layer "F.Fab")
			(hide yes)
			(effects
				(font
					(size 1 1)
					(thickness 0.15)
				)
			)
		)
		(property "Voltage" "10V"
			(at 0 0 180)
			(unlocked yes)
			(layer "F.Fab")
			(hide yes)
			(effects
				(font
					(size 1 1)
					(thickness 0.15)
				)
			)
		)
		(property "Dielectric" "X7R"
			(at 0 0 180)
			(unlocked yes)
			(layer "F.Fab")
			(hide yes)
			(effects
				(font
					(size 1 1)
					(thickness 0.15)
				)
			)
		)
		(property "Manufacturer" "Murata"
			(at 0 0 180)
			(unlocked yes)
			(layer "F.Fab")
			(hide yes)
			(effects
				(font
					(size 1 1)
					(thickness 0.15)
				)
			)
		)
		(property "License" "Apache-2.0"
			(at 0 0 180)
			(unlocked yes)
			(layer "F.Fab")
			(hide yes)
			(effects
				(font
					(size 1 1)
					(thickness 0.15)
				)
			)
		)
		(property "Author" "Antmicro"
			(at 0 0 180)
			(unlocked yes)
			(layer "F.Fab")
			(hide yes)
			(effects
				(font
					(size 1 1)
					(thickness 0.15)
				)
			)
		)
		(sheetname "/X710-AT2 power/")
		(sheetfile "x710-at2-power.kicad_sch")
		(attr smd)
		(fp_line
			(start -0.15 0.4)
			(end 0.15 0.4)
			(stroke
				(width 0.15)
				(type solid)
			)
			(layer "F.SilkS")
		)
		(fp_line
			(start -0.15 -0.4)
			(end 0.15 -0.4)
			(stroke
				(width 0.15)
				(type solid)
			)
			(layer "F.SilkS")
		)
		(fp_rect
			(start -1.25 -0.65)
			(end 1.25 0.65)
			(stroke
				(width 0.05)
				(type solid)
			)
			(fill no)
			(layer "F.CrtYd")
		)
		(fp_rect
			(start -0.8 -0.4)
			(end 0.8 0.4)
			(stroke
				(width 0.15)
				(type solid)
			)
			(fill no)
			(layer "F.Fab")
		)
		(fp_text user "License: Apache-2.0"
			(at -1.682 5.895 180)
			(layer "F.Fab")
			(effects
				(font
					(size 0.7 0.7)
					(thickness 0.15)
				)
				(justify left bottom)
			)
		)
		(fp_text user "${REFERENCE}"
			(at -1.682 3.895 180)
			(layer "F.Fab")
			(effects
				(font
					(size 0.7 0.7)
					(thickness 0.15)
				)
				(justify left bottom)
			)
		)
		(fp_text user "Author: Antmicro"
			(at -1.682 4.894 180)
			(layer "F.Fab")
			(effects
				(font
					(size 0.7 0.7)
					(thickness 0.15)
				)
				(justify left bottom)
			)
		)
		(pad "1" smd roundrect
			(at -0.7 0 180)
			(size 0.8 1)
			(layers "F.Cu" "F.Mask" "F.Paste")
			(roundrect_rratio 0.2)
			(net 23 "GND")
			(pintype "passive")
		)
		(pad "2" smd roundrect
			(at 0.7 0 180)
			(size 0.8 1)
			(layers "F.Cu" "F.Mask" "F.Paste")
			(roundrect_rratio 0.2)
			(net 5 "P0_AVDDL")
			(pintype "passive")
		)
	)
	(footprint "antmicro-footprints:R_0402_1005Metric"
		(layer "F.Cu")
		(at 172.6 72.1 90)
		(descr "Resistor SMD 0402")
		(tags "resistor SMD 0402")
		(property "Reference" "R186"
			(at 0.9 0.4 90)
			(layer "F.SilkS")
			(effects
				(font
					(size 0.7 0.7)
					(thickness 0.15)
				)
				(justify left bottom)
			)
		)
		(property "Value" "R_10R_0402"
			(at -1.011843 1.772047 90)
			(layer "F.Fab")
			(effects
				(font
					(size 0.7 0.7)
					(thickness 0.15)
				)
				(justify left bottom)
			)
		)
		(property "Datasheet" "https://www.bourns.com/docs/product-datasheets/cr.pdf"
			(at 0 0 90)
			(layer "F.Fab")
			(hide yes)
			(effects
				(font
					(size 1.27 1.27)
					(thickness 0.15)
				)
			)
		)
		(property "Description" "SMD Chip Resistor, 10 ohm, ± 1%, 62.5 mW, 0402 [1005 Metric], Thick Film, General Purpose"
			(at 0 0 90)
			(layer "F.Fab")
			(hide yes)
			(effects
				(font
					(size 1.27 1.27)
					(thickness 0.15)
				)
			)
		)
		(property "MPN" "CR0402-FX-10R0GLF"
			(at 0 0 90)
			(unlocked yes)
			(layer "F.Fab")
			(hide yes)
			(effects
				(font
					(size 1 1)
					(thickness 0.15)
				)
			)
		)
		(property "Manufacturer" "Bourns"
			(at 0 0 90)
			(unlocked yes)
			(layer "F.Fab")
			(hide yes)
			(effects
				(font
					(size 1 1)
					(thickness 0.15)
				)
			)
		)
		(property "License" "Apache-2.0"
			(at 0 0 90)
			(unlocked yes)
			(layer "F.Fab")
			(hide yes)
			(effects
				(font
					(size 1 1)
					(thickness 0.15)
				)
			)
		)
		(property "Author" "Antmicro"
			(at 0 0 90)
			(unlocked yes)
			(layer "F.Fab")
			(hide yes)
			(effects
				(font
					(size 1 1)
					(thickness 0.15)
				)
			)
		)
		(property "Val" "10R"
			(at 0 0 90)
			(unlocked yes)
			(layer "F.Fab")
			(hide yes)
			(effects
				(font
					(size 1 1)
					(thickness 0.15)
				)
			)
		)
		(property "Tolerance" "1%"
			(at 0 0 90)
			(unlocked yes)
			(layer "F.Fab")
			(hide yes)
			(effects
				(font
					(size 1 1)
					(thickness 0.15)
				)
			)
		)
		(sheetname "/X710-AT2 10GbE/")
		(sheetfile "x710-at2-10gbe.kicad_sch")
		(attr smd)
		(fp_rect
			(start -0.925 -0.47)
			(end 0.925 0.47)
			(stroke
				(width 0.05)
				(type default)
			)
			(fill no)
			(layer "F.CrtYd")
		)
		(fp_rect
			(start -0.5 -0.25)
			(end 0.5 0.25)
			(stroke
				(width 0.15)
				(type solid)
			)
			(fill no)
			(layer "F.Fab")
		)
		(fp_text user "Author: Antmicro"
			(at -0.95 4.169 90)
			(layer "F.Fab")
			(effects
				(font
					(size 0.7 0.7)
					(thickness 0.15)
				)
				(justify left bottom)
			)
		)
		(fp_text user "${REFERENCE}"
			(at -0.95 3.168 90)
			(layer "F.Fab")
			(effects
				(font
					(size 0.7 0.7)
					(thickness 0.15)
				)
				(justify left bottom)
			)
		)
		(fp_text user "License: Apache-2.0"
			(at -0.95 5.169 90)
			(layer "F.Fab")
			(effects
				(font
					(size 0.7 0.7)
					(thickness 0.15)
				)
				(justify left bottom)
			)
		)
		(pad "1" smd roundrect
			(at -0.48 0 90)
			(size 0.59 0.64)
			(layers "F.Cu" "F.Mask" "F.Paste")
			(roundrect_rratio 0.25)
			(net 125 "/X710-AT2 10GbE/MDIO0_I2C0.MDC")
			(pintype "passive")
		)
		(pad "2" smd roundrect
			(at 0.48 0 90)
			(size 0.59 0.64)
			(layers "F.Cu" "F.Mask" "F.Paste")
			(roundrect_rratio 0.25)
			(net 100 "/X710-AT2 10GbE/MDC0_SCL0")
			(pintype "passive")
		)
	)
)
